(kicad_pcb
	(version 20260206)
	(generator "pcbnew")
	(generator_version "10.0")
	(general
		(thickness 1.6)
		(legacy_teardrops no)
	)
	(paper "A4")
	(title_block
		(title "Bryce Canyon_F.DPB_16315-1-OCP.brd")
		(comment 1 "Bryce Canyon / footprints 281-288 of 2223")
	)
	(layers
		(0 "F.Cu" signal "TOP")
		(4 "In1.Cu" signal "L2GND")
		(6 "In2.Cu" signal "L3")
		(8 "In3.Cu" signal "L4GND")
		(10 "In4.Cu" signal "L5")
		(12 "In5.Cu" signal "L6VCC")
		(14 "In6.Cu" signal "L7VCC")
		(16 "In7.Cu" signal "L8")
		(18 "In8.Cu" signal "L9GND")
		(20 "In9.Cu" signal "L10")
		(22 "In10.Cu" signal "L11GND")
		(2 "B.Cu" signal "BOTTOM")
		(9 "F.Adhes" user "F.Adhesive")
		(11 "B.Adhes" user "B.Adhesive")
		(13 "F.Paste" user "Package Geometry/Pastemask Top")
		(15 "B.Paste" user "Package Geometry/Pastemask Bottom")
		(5 "F.SilkS" user "Ref Des/Silkscreen Top")
		(7 "B.SilkS" user "Ref Des/Silkscreen Bottom")
		(1 "F.Mask" user "Board Geometry/Soldermask Top")
		(3 "B.Mask" user "Board Geometry/Soldermask Bottom")
		(17 "Dwgs.User" user "User.Drawings")
		(19 "Cmts.User" user "User.Comments")
		(21 "Eco1.User" user "User.Eco1")
		(23 "Eco2.User" user "User.Eco2")
		(25 "Edge.Cuts" user "Board Geometry/Outline")
		(27 "Margin" user)
		(31 "F.CrtYd" user "Package Geometry/Place Bound Top")
		(29 "B.CrtYd" user "Package Geometry/Place Bound Bottom")
		(35 "F.Fab" user "Ref Des/Assembly Top")
		(33 "B.Fab" user "Ref Des/Assembly Bottom")
	)
	(footprint ""
		(layer "F.Cu")
		(at 86.121748 -44.821094 -90)
		(property "Reference" "R739"
			(at 0 0 270)
			(layer "F.SilkS")
			(hide yes)
			(effects
				(font
					(size 1.27 1.27)
				)
			)
		)
		(property "Value" "0R2J-2-GP"
			(at 0.064008 -3.993896 270)
			(unlocked yes)
			(layer "F.Fab")
			(hide yes)
			(effects
				(font
					(size 1.016 1.016)
					(thickness 0.1524)
				)
			)
		)
		(property "Device Type" "R402H16"
			(at 0.064008 -5.517896 270)
			(unlocked yes)
			(layer "F.Fab")
			(hide yes)
			(effects
				(font
					(size 1.016 1.016)
					(thickness 0.1524)
				)
			)
		)
		(duplicate_pad_numbers_are_jumpers no)
		(fp_line
			(start -0.508 -0.9398)
			(end -0.508 0.9398)
			(stroke
				(width 0.1524)
				(type default)
			)
			(layer "F.SilkS")
		)
		(fp_line
			(start 0.508 -0.9398)
			(end -0.508 -0.9398)
			(stroke
				(width 0.1524)
				(type default)
			)
			(layer "F.SilkS")
		)
		(fp_rect
			(start -0.508 0.9398)
			(end 0.508 -0.9398)
			(stroke
				(width 0)
				(type default)
			)
			(fill no)
			(layer "F.CrtYd")
		)
		(fp_rect
			(start -0.508 0.9398)
			(end 0.508 -0.9398)
			(stroke
				(width 0)
				(type default)
			)
			(fill no)
			(layer "F.Fab")
		)
		(pad "1" smd custom
			(at 0 -0.4445 270)
			(size 0.1397 0.1397)
			(layers "F.Cu" "F.Mask" "F.Paste")
			(net "DRIVE_A_26_PWR")
			(options
				(clearance outline)
				(anchor circle)
			)
			(primitives
				(gr_poly
					(pts
						(arc
							(start -0.1778 -0.2794)
							(mid -0.249642 -0.249642)
							(end -0.2794 -0.1778)
						)
						(arc
							(start -0.2794 0.1778)
							(mid -0.249642 0.249642)
							(end -0.1778 0.2794)
						)
						(arc
							(start 0.1778 0.2794)
							(mid 0.249642 0.249642)
							(end 0.2794 0.1778)
						)
						(arc
							(start 0.2794 -0.1778)
							(mid 0.249642 -0.249642)
							(end 0.1778 -0.2794)
						)
					)
					(width 0)
					(fill yes)
				)
			)
		)
		(pad "2" smd custom
			(at 0 0.4445 270)
			(size 0.1397 0.1397)
			(layers "F.Cu" "F.Mask" "F.Paste")
			(net "SW_PWR_R_HDD26")
			(options
				(clearance outline)
				(anchor circle)
			)
			(primitives
				(gr_poly
					(pts
						(arc
							(start -0.1778 -0.2794)
							(mid -0.249642 -0.249642)
							(end -0.2794 -0.1778)
						)
						(arc
							(start -0.2794 0.1778)
							(mid -0.249642 0.249642)
							(end -0.1778 0.2794)
						)
						(arc
							(start 0.1778 0.2794)
							(mid 0.249642 0.249642)
							(end 0.2794 0.1778)
						)
						(arc
							(start 0.2794 -0.1778)
							(mid 0.249642 -0.249642)
							(end 0.1778 -0.2794)
						)
					)
					(width 0)
					(fill yes)
				)
			)
		)
	)
	(footprint ""
		(layer "F.Cu")
		(at 269.57655 11.6078 180)
		(property "Reference" "R139"
			(at 0 0 180)
			(layer "F.SilkS")
			(hide yes)
			(effects
				(font
					(size 1.27 1.27)
				)
			)
		)
		(property "Value" "4K7R2F-GP"
			(at 0.064008 -3.993896 180)
			(unlocked yes)
			(layer "F.Fab")
			(hide yes)
			(effects
				(font
					(size 1.016 1.016)
					(thickness 0.1524)
				)
			)
		)
		(property "Device Type" "R402H16"
			(at 0.064008 -5.517896 180)
			(unlocked yes)
			(layer "F.Fab")
			(hide yes)
			(effects
				(font
					(size 1.016 1.016)
					(thickness 0.1524)
				)
			)
		)
		(duplicate_pad_numbers_are_jumpers no)
		(fp_line
			(start 0.508 -0.9398)
			(end -0.508 -0.9398)
			(stroke
				(width 0.1524)
				(type default)
			)
			(layer "F.SilkS")
		)
		(fp_line
			(start -0.508 -0.9398)
			(end -0.508 0.9398)
			(stroke
				(width 0.1524)
				(type default)
			)
			(layer "F.SilkS")
		)
		(fp_rect
			(start -0.508 0.9398)
			(end 0.508 -0.9398)
			(stroke
				(width 0)
				(type default)
			)
			(fill no)
			(layer "F.CrtYd")
		)
		(fp_rect
			(start -0.508 0.9398)
			(end 0.508 -0.9398)
			(stroke
				(width 0)
				(type default)
			)
			(fill no)
			(layer "F.Fab")
		)
		(pad "1" smd custom
			(at 0 -0.4445 180)
			(size 0.1397 0.1397)
			(layers "F.Cu" "F.Mask" "F.Paste")
			(net "USB_EN_2")
			(options
				(clearance outline)
				(anchor circle)
			)
			(primitives
				(gr_poly
					(pts
						(arc
							(start -0.1778 -0.2794)
							(mid -0.249642 -0.249642)
							(end -0.2794 -0.1778)
						)
						(arc
							(start -0.2794 0.1778)
							(mid -0.249642 0.249642)
							(end -0.1778 0.2794)
						)
						(arc
							(start 0.1778 0.2794)
							(mid 0.249642 0.249642)
							(end 0.2794 0.1778)
						)
						(arc
							(start 0.2794 -0.1778)
							(mid 0.249642 -0.249642)
							(end 0.1778 -0.2794)
						)
					)
					(width 0)
					(fill yes)
				)
			)
		)
		(pad "2" smd custom
			(at 0 0.4445 180)
			(size 0.1397 0.1397)
			(layers "F.Cu" "F.Mask" "F.Paste")
			(net "GND")
			(options
				(clearance outline)
				(anchor circle)
			)
			(primitives
				(gr_poly
					(pts
						(arc
							(start -0.1778 -0.2794)
							(mid -0.249642 -0.249642)
							(end -0.2794 -0.1778)
						)
						(arc
							(start -0.2794 0.1778)
							(mid -0.249642 0.249642)
							(end -0.1778 0.2794)
						)
						(arc
							(start 0.1778 0.2794)
							(mid 0.249642 0.249642)
							(end 0.2794 0.1778)
						)
						(arc
							(start 0.2794 -0.1778)
							(mid 0.249642 -0.249642)
							(end 0.1778 -0.2794)
						)
					)
					(width 0)
					(fill yes)
				)
			)
		)
	)
	(footprint ""
		(layer "F.Cu")
		(at 174.5742 -53.152294 -90)
		(property "Reference" "C425"
			(at 0 0 270)
			(layer "F.SilkS")
			(hide yes)
			(effects
				(font
					(size 1.27 1.27)
				)
			)
		)
		(property "Value" "SCD033U25V2KX-GP"
			(at 1.1811 -2.7051 270)
			(unlocked yes)
			(layer "F.Fab")
			(hide yes)
			(effects
				(font
					(size 1.016 1.016)
					(thickness 0.1524)
				)
			)
		)
		(property "Device Type" "C402H22"
			(at 1.1811 -4.2291 270)
			(unlocked yes)
			(layer "F.Fab")
			(hide yes)
			(effects
				(font
					(size 1.016 1.016)
					(thickness 0.1524)
				)
			)
		)
		(duplicate_pad_numbers_are_jumpers no)
		(fp_rect
			(start -0.4318 0.9525)
			(end 0.4318 -0.9525)
			(stroke
				(width 0)
				(type default)
			)
			(fill no)
			(layer "F.CrtYd")
		)
		(fp_rect
			(start -0.4318 0.9525)
			(end 0.4318 -0.9525)
			(stroke
				(width 0)
				(type default)
			)
			(fill no)
			(layer "F.Fab")
		)
		(pad "1" smd custom
			(at 0 -0.4445 270)
			(size 0.1524 0.1524)
			(layers "F.Cu" "F.Mask" "F.Paste")
			(net "SW_HDD_P29")
			(options
				(clearance outline)
				(anchor circle)
			)
			(primitives
				(gr_poly
					(pts
						(arc
							(start 0.3048 -0.2032)
							(mid 0.275042 -0.275042)
							(end 0.2032 -0.3048)
						)
						(arc
							(start -0.2032 -0.3048)
							(mid -0.275042 -0.275042)
							(end -0.3048 -0.2032)
						)
						(arc
							(start -0.3048 0.2032)
							(mid -0.275042 0.275042)
							(end -0.2032 0.3048)
						)
						(arc
							(start 0.2032 0.3048)
							(mid 0.275042 0.275042)
							(end 0.3048 0.2032)
						)
					)
					(width 0)
					(fill yes)
				)
			)
		)
		(pad "2" smd custom
			(at 0 0.4445 270)
			(size 0.1524 0.1524)
			(layers "F.Cu" "F.Mask" "F.Paste")
			(net "GND")
			(options
				(clearance outline)
				(anchor circle)
			)
			(primitives
				(gr_poly
					(pts
						(arc
							(start 0.3048 -0.2032)
							(mid 0.275042 -0.275042)
							(end 0.2032 -0.3048)
						)
						(arc
							(start -0.2032 -0.3048)
							(mid -0.275042 -0.275042)
							(end -0.3048 -0.2032)
						)
						(arc
							(start -0.3048 0.2032)
							(mid -0.275042 0.275042)
							(end -0.2032 0.3048)
						)
						(arc
							(start 0.2032 0.3048)
							(mid 0.275042 0.275042)
							(end 0.3048 0.2032)
						)
					)
					(width 0)
					(fill yes)
				)
			)
		)
	)
	(footprint ""
		(layer "F.Cu")
		(at 256.9718 -238.506 -90)
		(property "Reference" "C30"
			(at 0 0 270)
			(layer "F.SilkS")
			(hide yes)
			(effects
				(font
					(size 1.27 1.27)
				)
			)
		)
		(property "Value" "SCD1U16V2KX-3GP"
			(at 1.1811 -2.7051 270)
			(unlocked yes)
			(layer "F.Fab")
			(hide yes)
			(effects
				(font
					(size 1.016 1.016)
					(thickness 0.1524)
				)
			)
		)
		(property "Device Type" "C402H22"
			(at 1.1811 -4.2291 270)
			(unlocked yes)
			(layer "F.Fab")
			(hide yes)
			(effects
				(font
					(size 1.016 1.016)
					(thickness 0.1524)
				)
			)
		)
		(duplicate_pad_numbers_are_jumpers no)
		(fp_rect
			(start -0.4318 0.9525)
			(end 0.4318 -0.9525)
			(stroke
				(width 0)
				(type default)
			)
			(fill no)
			(layer "F.CrtYd")
		)
		(fp_rect
			(start -0.4318 0.9525)
			(end 0.4318 -0.9525)
			(stroke
				(width 0)
				(type default)
			)
			(fill no)
			(layer "F.Fab")
		)
		(pad "1" smd custom
			(at 0 -0.4445 270)
			(size 0.1524 0.1524)
			(layers "F.Cu" "F.Mask" "F.Paste")
			(net "GPIO_VCC_U9")
			(options
				(clearance outline)
				(anchor circle)
			)
			(primitives
				(gr_poly
					(pts
						(arc
							(start 0.3048 -0.2032)
							(mid 0.275042 -0.275042)
							(end 0.2032 -0.3048)
						)
						(arc
							(start -0.2032 -0.3048)
							(mid -0.275042 -0.275042)
							(end -0.3048 -0.2032)
						)
						(arc
							(start -0.3048 0.2032)
							(mid -0.275042 0.275042)
							(end -0.2032 0.3048)
						)
						(arc
							(start 0.2032 0.3048)
							(mid 0.275042 0.275042)
							(end 0.3048 0.2032)
						)
					)
					(width 0)
					(fill yes)
				)
			)
		)
		(pad "2" smd custom
			(at 0 0.4445 270)
			(size 0.1524 0.1524)
			(layers "F.Cu" "F.Mask" "F.Paste")
			(net "GND")
			(options
				(clearance outline)
				(anchor circle)
			)
			(primitives
				(gr_poly
					(pts
						(arc
							(start 0.3048 -0.2032)
							(mid 0.275042 -0.275042)
							(end 0.2032 -0.3048)
						)
						(arc
							(start -0.2032 -0.3048)
							(mid -0.275042 -0.275042)
							(end -0.3048 -0.2032)
						)
						(arc
							(start -0.3048 0.2032)
							(mid -0.275042 0.275042)
							(end -0.2032 0.3048)
						)
						(arc
							(start 0.2032 0.3048)
							(mid 0.275042 0.275042)
							(end 0.3048 0.2032)
						)
					)
					(width 0)
					(fill yes)
				)
			)
		)
	)
	(footprint ""
		(layer "F.Cu")
		(at 49.349914 -324.39991)
		(property "Reference" "RLED26"
			(at 0 0 0)
			(layer "F.SilkS")
			(hide yes)
			(effects
				(font
					(size 1.27 1.27)
				)
			)
		)
		(property "Value" "LED-BY-19-GP"
			(at -2.132076 1.414018 0)
			(unlocked yes)
			(layer "F.Fab")
			(hide yes)
			(effects
				(font
					(size 1.016 1.016)
					(thickness 0.1524)
				)
			)
		)
		(property "Device Type" "LED-1615-4PH26"
			(at -2.132076 -0.109982 0)
			(unlocked yes)
			(layer "F.Fab")
			(hide yes)
			(effects
				(font
					(size 1.016 1.016)
					(thickness 0.1524)
				)
			)
		)
		(duplicate_pad_numbers_are_jumpers no)
		(fp_line
			(start -1.2954 0.254)
			(end -1.2954 1.6002)
			(stroke
				(width 0.508)
				(type default)
			)
			(layer "F.SilkS")
		)
		(fp_line
			(start -1.2954 1.6002)
			(end 1.2954 1.6002)
			(stroke
				(width 0.508)
				(type default)
			)
			(layer "F.SilkS")
		)
		(fp_line
			(start -1.1176 -1.4224)
			(end 1.1176 -1.4224)
			(stroke
				(width 0.1524)
				(type default)
			)
			(layer "F.SilkS")
		)
		(fp_line
			(start -1.1176 1.4224)
			(end -1.1176 -1.4224)
			(stroke
				(width 0.1524)
				(type default)
			)
			(layer "F.SilkS")
		)
		(fp_line
			(start 1.1176 -1.4224)
			(end 1.1176 1.4224)
			(stroke
				(width 0.1524)
				(type default)
			)
			(layer "F.SilkS")
		)
		(fp_line
			(start 1.1176 1.4224)
			(end -1.1176 1.4224)
			(stroke
				(width 0.1524)
				(type default)
			)
			(layer "F.SilkS")
		)
		(fp_line
			(start 1.2954 1.6002)
			(end 1.2954 0.254)
			(stroke
				(width 0.508)
				(type default)
			)
			(layer "F.SilkS")
		)
		(fp_rect
			(start -0.7493 0.8001)
			(end 0.7493 -0.8001)
			(stroke
				(width 0)
				(type default)
			)
			(fill no)
			(layer "F.CrtYd")
		)
		(fp_poly
			(pts
				(xy -1.3716 1.6764) (xy -1.3716 -1.6764) (xy 1.3716 -1.6764) (xy 1.3716 0.0635) (xy 0.7493 0.0635)
				(xy 0.7493 -0.8001) (xy -0.7493 -0.8001) (xy -0.7493 0.8001) (xy 0.7493 0.8001) (xy 0.7493 0.0762)
				(xy 1.3716 0.0762) (xy 1.3716 1.6764)
			)
			(stroke
				(width 0)
				(type default)
			)
			(fill no)
			(layer "F.CrtYd")
		)
		(fp_rect
			(start -1.3716 1.6764)
			(end 1.3716 -1.6764)
			(stroke
				(width 0)
				(type default)
			)
			(fill no)
			(layer "F.Fab")
		)
		(pad "1" smd rect
			(at 0.50038 -0.73025)
			(size 0.7112 0.8636)
			(layers "F.Cu" "F.Mask" "F.Paste")
			(net "DRV_ACT_25")
		)
		(pad "2" smd rect
			(at -0.50038 -0.73025)
			(size 0.7112 0.8636)
			(layers "F.Cu" "F.Mask" "F.Paste")
			(net "FLT_HDD25")
		)
		(pad "3" smd rect
			(at 0.50038 0.73025)
			(size 0.7112 0.8636)
			(layers "F.Cu" "F.Mask" "F.Paste")
			(net "DRV_ACT_25_N")
		)
		(pad "4" smd rect
			(at -0.50038 0.73025)
			(size 0.7112 0.8636)
			(layers "F.Cu" "F.Mask" "F.Paste")
			(net "FLT_HDD25_N")
		)
	)
	(footprint ""
		(layer "F.Cu")
		(at 224.553526 -149.120098 -90)
		(property "Reference" "TP225"
			(at 0 0 270)
			(layer "F.SilkS")
			(hide yes)
			(effects
				(font
					(size 1.27 1.27)
				)
			)
		)
		(property "Value" "TPAD32-GP"
			(at -0.0508 -1.6764 270)
			(unlocked yes)
			(layer "F.Fab")
			(hide yes)
			(effects
				(font
					(size 1.016 1.016)
					(thickness 0.1524)
				)
			)
		)
		(property "Device Type" "TPAD32"
			(at -0.0508 -3.2004 270)
			(unlocked yes)
			(layer "F.Fab")
			(hide yes)
			(effects
				(font
					(size 1.016 1.016)
					(thickness 0.1524)
				)
			)
		)
		(duplicate_pad_numbers_are_jumpers no)
		(fp_poly
			(pts
				(arc
					(start 0 -0.4064)
					(mid 0 0.4064)
					(end 0 -0.4064)
				)
			)
			(stroke
				(width 0)
				(type default)
			)
			(fill no)
			(layer "F.CrtYd")
		)
		(fp_poly
			(pts
				(arc
					(start 0 -0.7112)
					(mid 0 0.7112)
					(end 0 -0.7112)
				)
			)
			(stroke
				(width 0)
				(type default)
			)
			(fill no)
			(layer "F.Fab")
		)
		(pad "1" smd circle
			(at 0 0 270)
			(size 0.8128 0.8128)
			(layers "F.Cu" "F.Mask" "F.Paste")
			(net "TP_SMB_COMP_A_NIC_SDA")
		)
	)
	(footprint ""
		(layer "F.Cu")
		(at 399.14195 -163.300918 90)
		(property "Reference" "D20"
			(at 0 0 90)
			(layer "F.SilkS")
			(hide yes)
			(effects
				(font
					(size 1.27 1.27)
				)
			)
		)
		(property "Value" "RB551V30-GP"
			(at 0 -6.7818 90)
			(unlocked yes)
			(layer "F.Fab")
			(hide yes)
			(effects
				(font
					(size 1.016 1.016)
					(thickness 0.1524)
				)
			)
		)
		(property "Device Type" "SOD323AKH38"
			(at 0 -8.6868 90)
			(unlocked yes)
			(layer "F.Fab")
			(hide yes)
			(effects
				(font
					(size 1.016 1.016)
					(thickness 0.1524)
				)
			)
		)
		(duplicate_pad_numbers_are_jumpers no)
		(fp_line
			(start 0.889 -1.9304)
			(end 0.889 2.159)
			(stroke
				(width 0.1524)
				(type default)
			)
			(layer "F.SilkS")
		)
		(fp_line
			(start -0.889 -1.9304)
			(end 0.889 -1.9304)
			(stroke
				(width 0.1524)
				(type default)
			)
			(layer "F.SilkS")
		)
		(fp_line
			(start 0.762 2.0574)
			(end -0.762 2.0574)
			(stroke
				(width 0.508)
				(type default)
			)
			(layer "F.SilkS")
		)
		(fp_line
			(start 0.889 2.159)
			(end -0.889 2.159)
			(stroke
				(width 0.1524)
				(type default)
			)
			(layer "F.SilkS")
		)
		(fp_line
			(start -0.889 2.159)
			(end -0.889 -1.9304)
			(stroke
				(width 0.1524)
				(type default)
			)
			(layer "F.SilkS")
		)
		(fp_rect
			(start -1.016 2.3114)
			(end 1.016 -2.0066)
			(stroke
				(width 0)
				(type default)
			)
			(fill no)
			(layer "F.CrtYd")
		)
		(fp_poly
			(pts
				(xy -1.016 -2.0066) (xy 1.016 -2.0066) (xy 1.016 2.3114) (xy -1.016 2.3114)
			)
			(stroke
				(width 0)
				(type default)
			)
			(fill no)
			(layer "F.Fab")
		)
		(pad "A" smd rect
			(at 0 -1.143 90)
			(size 0.5588 1.016)
			(layers "F.Cu" "F.Mask" "F.Paste")
			(net "SW_HDD_R20")
		)
		(pad "K" smd rect
			(at 0 1.143 90)
			(size 0.5588 1.016)
			(layers "F.Cu" "F.Mask" "F.Paste")
			(net "SW_HDD_N20")
		)
	)
	(footprint ""
		(layer "F.Cu")
		(at 455.203052 -246.047006 -90)
		(property "Reference" "R496"
			(at 0 0 270)
			(layer "F.SilkS")
			(hide yes)
			(effects
				(font
					(size 1.27 1.27)
				)
			)
		)
		(property "Value" "4K7R2J-2-GP"
			(at 0.064008 -3.993896 270)
			(unlocked yes)
			(layer "F.Fab")
			(hide yes)
			(effects
				(font
					(size 1.016 1.016)
					(thickness 0.1524)
				)
			)
		)
		(property "Device Type" "R402H16"
			(at 0.064008 -5.517896 270)
			(unlocked yes)
			(layer "F.Fab")
			(hide yes)
			(effects
				(font
					(size 1.016 1.016)
					(thickness 0.1524)
				)
			)
		)
		(duplicate_pad_numbers_are_jumpers no)
		(fp_line
			(start -0.508 -0.9398)
			(end -0.508 0.9398)
			(stroke
				(width 0.1524)
				(type default)
			)
			(layer "F.SilkS")
		)
		(fp_line
			(start 0.508 -0.9398)
			(end -0.508 -0.9398)
			(stroke
				(width 0.1524)
				(type default)
			)
			(layer "F.SilkS")
		)
		(fp_rect
			(start -0.508 0.9398)
			(end 0.508 -0.9398)
			(stroke
				(width 0)
				(type default)
			)
			(fill no)
			(layer "F.CrtYd")
		)
		(fp_rect
			(start -0.508 0.9398)
			(end 0.508 -0.9398)
			(stroke
				(width 0)
				(type default)
			)
			(fill no)
			(layer "F.Fab")
		)
		(pad "1" smd custom
			(at 0 -0.4445 270)
			(size 0.1397 0.1397)
			(layers "F.Cu" "F.Mask" "F.Paste")
			(net "DRIVE_A_11_ACT")
			(options
				(clearance outline)
				(anchor circle)
			)
			(primitives
				(gr_poly
					(pts
						(arc
							(start -0.1778 -0.2794)
							(mid -0.249642 -0.249642)
							(end -0.2794 -0.1778)
						)
						(arc
							(start -0.2794 0.1778)
							(mid -0.249642 0.249642)
							(end -0.1778 0.2794)
						)
						(arc
							(start 0.1778 0.2794)
							(mid 0.249642 0.249642)
							(end 0.2794 0.1778)
						)
						(arc
							(start 0.2794 -0.1778)
							(mid 0.249642 -0.249642)
							(end 0.1778 -0.2794)
						)
					)
					(width 0)
					(fill yes)
				)
			)
		)
		(pad "2" smd custom
			(at 0 0.4445 270)
			(size 0.1397 0.1397)
			(layers "F.Cu" "F.Mask" "F.Paste")
			(net "GND")
			(options
				(clearance outline)
				(anchor circle)
			)
			(primitives
				(gr_poly
					(pts
						(arc
							(start -0.1778 -0.2794)
							(mid -0.249642 -0.249642)
							(end -0.2794 -0.1778)
						)
						(arc
							(start -0.2794 0.1778)
							(mid -0.249642 0.249642)
							(end -0.1778 0.2794)
						)
						(arc
							(start 0.1778 0.2794)
							(mid 0.249642 0.249642)
							(end 0.2794 0.1778)
						)
						(arc
							(start 0.2794 -0.1778)
							(mid 0.249642 -0.249642)
							(end 0.1778 -0.2794)
						)
					)
					(width 0)
					(fill yes)
				)
			)
		)
	)
)
